(kicad_sch
	(version 20250114)
	(generator "eeschema")
	(generator_version "9.0")
	(paper "A3")
	(title_block
		(title "Thunderbolt to 10GbE adapter")
		(date "2026-04-23")
		(rev "1.1.0")
		(company "Antmicro Ltd")
		(comment 1 "www.antmicro.com")
	)
	(text "Fan Controller"
		(exclude_from_sim no)
		(at 204.47 100.33 0)
		(effects
			(font
				(size 2.54 2.54)
				(thickness 0.508)
				(bold yes)
			)
		)
	)
	(text "100%"
		(exclude_from_sim no)
		(at 198.882 255.524 0)
		(effects
			(font
				(size 1.27 1.27)
			)
			(justify right)
		)
	)
	(text "0%"
		(exclude_from_sim no)
		(at 198.882 270.764 0)
		(effects
			(font
				(size 1.27 1.27)
			)
			(justify right)
		)
	)
	(text "Duty cycle [%]"
		(exclude_from_sim no)
		(at 199.39 252.73 0)
		(effects
			(font
				(size 1.27 1.27)
			)
		)
	)
	(text "T[°C]"
		(exclude_from_sim no)
		(at 225.298 270.764 0)
		(effects
			(font
				(size 1.27 1.27)
			)
			(justify left)
		)
	)
	(text "38°C"
		(exclude_from_sim no)
		(at 203.2 272.288 0)
		(effects
			(font
				(size 1.27 1.27)
			)
		)
	)
	(text "50°C"
		(exclude_from_sim no)
		(at 218.44 272.288 0)
		(effects
			(font
				(size 1.27 1.27)
			)
		)
	)
	(text "18%"
		(exclude_from_sim no)
		(at 198.882 266.954 0)
		(effects
			(font
				(size 1.27 1.27)
			)
			(justify right)
		)
	)
	(text_box "Select this resistance equal\nto the resistance of the \nthermistor at the\ndesired value of TSTART.\n\nTSTART ≈ 38°C"
		(exclude_from_sim no)
		(at 123.19 123.19 0)
		(size 39.37 12.7)
		(margins 0.9525 0.9525 0.9525 0.9525)
		(stroke
			(width 0)
			(type solid)
		)
		(fill
			(type none)
		)
		(effects
			(font
				(size 1.27 1.27)
			)
			(justify left)
		)
	)
	(text_box "D_{MIN} = 2 * R_{L}/(R_{L}+R_{H}) [%]\n\nD_{MIN} = 2 * 1k/(1k+10k) = 18%"
		(exclude_from_sim no)
		(at 137.16 165.1 0)
		(size 45.72 17.78)
		(margins 0.9525 0.9525 0.9525 0.9525)
		(stroke
			(width 0)
			(type solid)
		)
		(fill
			(type none)
		)
		(effects
			(font
				(size 1.27 1.27)
			)
			(justify left)
		)
	)
	(text_box "Reference"
		(exclude_from_sim no)
		(at 161.29 213.36 0)
		(size 99.06 3.81)
		(margins 0.9525 0.9525 0.9525 0.9525)
		(stroke
			(width 0)
			(type solid)
		)
		(fill
			(type none)
		)
		(effects
			(font
				(size 1.27 1.27)
			)
			(justify left top)
		)
	)
	(text_box "f_{PWM} = 10.5455E^{-6}/C [Hz]\n\nf_{PWM} = 22kHz"
		(exclude_from_sim no)
		(at 233.68 140.97 0)
		(size 41.91 7.62)
		(margins 0.9525 0.9525 0.9525 0.9525)
		(stroke
			(width 0)
			(type solid)
		)
		(fill
			(type none)
		)
		(effects
			(font
				(size 1.27 1.27)
			)
			(justify right)
		)
	)
	(text_box "Designed temperature curve"
		(exclude_from_sim no)
		(at 191.77 246.38 0)
		(size 39.37 27.94)
		(margins 0.9525 0.9525 0.9525 0.9525)
		(stroke
			(width 0)
			(type solid)
		)
		(fill
			(type none)
		)
		(effects
			(font
				(size 1.27 1.27)
			)
			(justify left top)
		)
	)
	(junction
		(at 180.34 173.99)
		(diameter 0)
		(color 0 0 0 0)
	)
	(junction
		(at 279.4 137.16)
		(diameter 0)
		(color 0 0 0 0)
	)
	(junction
		(at 180.34 163.83)
		(diameter 0)
		(color 0 0 0 0)
	)
	(junction
		(at 172.72 137.16)
		(diameter 0)
		(color 0 0 0 0)
	)
	(junction
		(at 218.44 147.32)
		(diameter 0)
		(color 0 0 0 0)
	)
	(junction
		(at 153.67 137.16)
		(diameter 0)
		(color 0 0 0 0)
	)
	(junction
		(at 185.42 123.19)
		(diameter 0)
		(color 0 0 0 0)
	)
	(junction
		(at 193.04 173.99)
		(diameter 0)
		(color 0 0 0 0)
	)
	(no_connect
		(at 269.24 134.62)
	)
	(polyline
		(pts
			(xy 203.2 266.7) (xy 218.44 255.27)
		)
		(stroke
			(width 0)
			(type default)
		)
	)
	(wire
		(pts
			(xy 185.42 144.78) (xy 193.04 144.78)
		)
		(stroke
			(width 0)
			(type default)
		)
	)
	(wire
		(pts
			(xy 215.9 137.16) (xy 237.49 137.16)
		)
		(stroke
			(width 0)
			(type default)
		)
	)
	(polyline
		(pts
			(xy 203.2 266.7) (xy 203.2 270.51)
		)
		(stroke
			(width 0)
			(type default)
		)
	)
	(polyline
		(pts
			(xy 199.39 266.7) (xy 203.2 266.7)
		)
		(stroke
			(width 0)
			(type dot)
		)
	)
	(wire
		(pts
			(xy 313.69 132.08) (xy 317.5 132.08)
		)
		(stroke
			(width 0)
			(type default)
		)
	)
	(wire
		(pts
			(xy 172.72 139.7) (xy 172.72 137.16)
		)
		(stroke
			(width 0)
			(type default)
		)
	)
	(wire
		(pts
			(xy 182.88 123.19) (xy 185.42 123.19)
		)
		(stroke
			(width 0)
			(type default)
		)
	)
	(polyline
		(pts
			(xy 218.44 255.27) (xy 224.79 255.27)
		)
		(stroke
			(width 0)
			(type default)
		)
	)
	(wire
		(pts
			(xy 279.4 149.86) (xy 279.4 139.7)
		)
		(stroke
			(width 0)
			(type default)
		)
	)
	(wire
		(pts
			(xy 237.49 142.24) (xy 237.49 137.16)
		)
		(stroke
			(width 0)
			(type default)
		)
	)
	(polyline
		(pts
			(xy 199.39 255.27) (xy 218.44 255.27)
		)
		(stroke
			(width 0)
			(type dot)
		)
	)
	(wire
		(pts
			(xy 153.67 121.92) (xy 153.67 127)
		)
		(stroke
			(width 0)
			(type default)
		)
	)
	(wire
		(pts
			(xy 237.49 149.86) (xy 237.49 147.32)
		)
		(stroke
			(width 0)
			(type default)
		)
	)
	(wire
		(pts
			(xy 168.91 137.16) (xy 172.72 137.16)
		)
		(stroke
			(width 0)
			(type default)
		)
	)
	(wire
		(pts
			(xy 218.44 147.32) (xy 218.44 149.86)
		)
		(stroke
			(width 0)
			(type default)
		)
	)
	(wire
		(pts
			(xy 187.96 147.32) (xy 187.96 173.99)
		)
		(stroke
			(width 0)
			(type default)
		)
	)
	(polyline
		(pts
			(xy 199.39 270.51) (xy 224.79 270.51)
		)
		(stroke
			(width 0)
			(type default)
		)
	)
	(wire
		(pts
			(xy 193.04 173.99) (xy 193.04 176.53)
		)
		(stroke
			(width 0)
			(type default)
		)
	)
	(wire
		(pts
			(xy 215.9 132.08) (xy 281.94 132.08)
		)
		(stroke
			(width 0)
			(type default)
		)
	)
	(polyline
		(pts
			(xy 191.77 250.19) (xy 231.14 250.19)
		)
		(stroke
			(width 0)
			(type default)
		)
	)
	(wire
		(pts
			(xy 313.69 148.59) (xy 317.5 148.59)
		)
		(stroke
			(width 0)
			(type default)
		)
	)
	(wire
		(pts
			(xy 187.96 173.99) (xy 193.04 173.99)
		)
		(stroke
			(width 0)
			(type default)
		)
	)
	(wire
		(pts
			(xy 269.24 134.62) (xy 281.94 134.62)
		)
		(stroke
			(width 0)
			(type default)
		)
	)
	(wire
		(pts
			(xy 176.53 163.83) (xy 180.34 163.83)
		)
		(stroke
			(width 0)
			(type default)
		)
	)
	(wire
		(pts
			(xy 193.04 163.83) (xy 193.04 166.37)
		)
		(stroke
			(width 0)
			(type default)
		)
	)
	(wire
		(pts
			(xy 172.72 147.32) (xy 172.72 144.78)
		)
		(stroke
			(width 0)
			(type default)
		)
	)
	(wire
		(pts
			(xy 182.88 124.46) (xy 182.88 123.19)
		)
		(stroke
			(width 0)
			(type default)
		)
	)
	(wire
		(pts
			(xy 172.72 137.16) (xy 193.04 137.16)
		)
		(stroke
			(width 0)
			(type default)
		)
	)
	(wire
		(pts
			(xy 269.24 137.16) (xy 279.4 137.16)
		)
		(stroke
			(width 0)
			(type default)
		)
	)
	(wire
		(pts
			(xy 187.96 147.32) (xy 193.04 147.32)
		)
		(stroke
			(width 0)
			(type default)
		)
	)
	(polyline
		(pts
			(xy 199.39 270.51) (xy 203.2 270.51)
		)
		(stroke
			(width 0)
			(type default)
		)
	)
	(wire
		(pts
			(xy 279.4 128.27) (xy 279.4 137.16)
		)
		(stroke
			(width 0)
			(type default)
		)
	)
	(wire
		(pts
			(xy 153.67 137.16) (xy 153.67 139.7)
		)
		(stroke
			(width 0)
			(type default)
		)
	)
	(wire
		(pts
			(xy 279.4 139.7) (xy 281.94 139.7)
		)
		(stroke
			(width 0)
			(type default)
		)
	)
	(polyline
		(pts
			(xy 218.44 270.51) (xy 218.44 255.27)
		)
		(stroke
			(width 0)
			(type dot)
		)
	)
	(wire
		(pts
			(xy 218.44 144.78) (xy 218.44 147.32)
		)
		(stroke
			(width 0)
			(type default)
		)
	)
	(wire
		(pts
			(xy 185.42 119.38) (xy 185.42 123.19)
		)
		(stroke
			(width 0)
			(type default)
		)
	)
	(wire
		(pts
			(xy 215.9 144.78) (xy 218.44 144.78)
		)
		(stroke
			(width 0)
			(type default)
		)
	)
	(wire
		(pts
			(xy 180.34 181.61) (xy 180.34 184.15)
		)
		(stroke
			(width 0)
			(type default)
		)
	)
	(wire
		(pts
			(xy 185.42 144.78) (xy 185.42 173.99)
		)
		(stroke
			(width 0)
			(type default)
		)
	)
	(wire
		(pts
			(xy 185.42 173.99) (xy 180.34 173.99)
		)
		(stroke
			(width 0)
			(type default)
		)
	)
	(wire
		(pts
			(xy 224.79 142.24) (xy 224.79 139.7)
		)
		(stroke
			(width 0)
			(type default)
		)
	)
	(wire
		(pts
			(xy 193.04 171.45) (xy 193.04 173.99)
		)
		(stroke
			(width 0)
			(type default)
		)
	)
	(wire
		(pts
			(xy 317.5 148.59) (xy 317.5 149.86)
		)
		(stroke
			(width 0)
			(type default)
		)
	)
	(wire
		(pts
			(xy 224.79 149.86) (xy 224.79 147.32)
		)
		(stroke
			(width 0)
			(type default)
		)
	)
	(wire
		(pts
			(xy 218.44 147.32) (xy 215.9 147.32)
		)
		(stroke
			(width 0)
			(type default)
		)
	)
	(wire
		(pts
			(xy 176.53 162.56) (xy 176.53 163.83)
		)
		(stroke
			(width 0)
			(type default)
		)
	)
	(wire
		(pts
			(xy 185.42 132.08) (xy 193.04 132.08)
		)
		(stroke
			(width 0)
			(type default)
		)
	)
	(wire
		(pts
			(xy 317.5 132.08) (xy 317.5 133.35)
		)
		(stroke
			(width 0)
			(type default)
		)
	)
	(wire
		(pts
			(xy 180.34 173.99) (xy 180.34 176.53)
		)
		(stroke
			(width 0)
			(type default)
		)
	)
	(wire
		(pts
			(xy 153.67 144.78) (xy 153.67 147.32)
		)
		(stroke
			(width 0)
			(type default)
		)
	)
	(wire
		(pts
			(xy 317.5 154.94) (xy 317.5 157.48)
		)
		(stroke
			(width 0)
			(type default)
		)
	)
	(polyline
		(pts
			(xy 199.39 254) (xy 199.39 270.51)
		)
		(stroke
			(width 0)
			(type default)
		)
	)
	(wire
		(pts
			(xy 317.5 138.43) (xy 317.5 140.97)
		)
		(stroke
			(width 0)
			(type default)
		)
	)
	(wire
		(pts
			(xy 193.04 181.61) (xy 193.04 184.15)
		)
		(stroke
			(width 0)
			(type default)
		)
	)
	(wire
		(pts
			(xy 185.42 123.19) (xy 185.42 132.08)
		)
		(stroke
			(width 0)
			(type default)
		)
	)
	(wire
		(pts
			(xy 153.67 137.16) (xy 163.83 137.16)
		)
		(stroke
			(width 0)
			(type default)
		)
	)
	(wire
		(pts
			(xy 180.34 163.83) (xy 180.34 166.37)
		)
		(stroke
			(width 0)
			(type default)
		)
	)
	(wire
		(pts
			(xy 153.67 132.08) (xy 153.67 137.16)
		)
		(stroke
			(width 0)
			(type default)
		)
	)
	(wire
		(pts
			(xy 281.94 137.16) (xy 279.4 137.16)
		)
		(stroke
			(width 0)
			(type default)
		)
	)
	(wire
		(pts
			(xy 180.34 163.83) (xy 193.04 163.83)
		)
		(stroke
			(width 0)
			(type default)
		)
	)
	(wire
		(pts
			(xy 215.9 139.7) (xy 224.79 139.7)
		)
		(stroke
			(width 0)
			(type default)
		)
	)
	(wire
		(pts
			(xy 180.34 171.45) (xy 180.34 173.99)
		)
		(stroke
			(width 0)
			(type default)
		)
	)
	(label "TACH"
		(at 269.24 134.62 0)
		(effects
			(font
				(size 1.27 1.27)
			)
			(justify left bottom)
		)
	)
	(label "D0"
		(at 190.5 147.32 180)
		(effects
			(font
				(size 1.27 1.27)
			)
			(justify right bottom)
		)
	)
	(label "SENSE"
		(at 190.5 137.16 180)
		(effects
			(font
				(size 1.27 1.27)
			)
			(justify right bottom)
		)
	)
	(label "V_{FAN}"
		(at 269.24 137.16 0)
		(effects
			(font
				(size 1.27 1.27)
			)
			(justify left bottom)
		)
	)
	(label "PWM"
		(at 269.24 132.08 0)
		(effects
			(font
				(size 1.27 1.27)
			)
			(justify left bottom)
		)
	)
	(label "DMIN"
		(at 190.5 144.78 180)
		(effects
			(font
				(size 1.27 1.27)
			)
			(justify right bottom)
		)
	)
	(label "V_{FAN}"
		(at 313.69 148.59 0)
		(effects
			(font
				(size 1.27 1.27)
			)
			(justify left bottom)
		)
	)
	(label "FREQ"
		(at 218.44 137.16 0)
		(effects
			(font
				(size 1.27 1.27)
			)
			(justify left bottom)
		)
	)
	(label "PWM"
		(at 313.69 132.08 0)
		(effects
			(font
				(size 1.27 1.27)
			)
			(justify left bottom)
		)
	)
	(label "SLOPE"
		(at 218.44 139.7 0)
		(effects
			(font
				(size 1.27 1.27)
			)
			(justify left bottom)
		)
	)
	(symbol
		(lib_id "antmicropower:GND")
		(at 224.79 149.86 0)
		(unit 1)
		(exclude_from_sim no)
		(in_bom yes)
		(on_board yes)
		(dnp no)
		(property "Reference" "#PWR0460"
			(at 233.68 152.4 0)
			(effects
				(font
					(size 1.27 1.27)
					(thickness 0.15)
				)
				(justify left bottom)
				(hide yes)
			)
		)
		(property "Value" "GND"
			(at 224.79 153.67 0)
			(effects
				(font
					(size 1.27 1.27)
					(thickness 0.15)
				)
			)
		)
		(property "Footprint" ""
			(at 233.68 157.48 0)
			(effects
				(font
					(size 1.27 1.27)
					(thickness 0.15)
				)
				(justify left bottom)
				(hide yes)
			)
		)
		(property "Datasheet" ""
			(at 233.68 162.56 0)
			(effects
				(font
					(size 1.27 1.27)
					(thickness 0.15)
				)
				(justify left bottom)
				(hide yes)
			)
		)
		(property "Description" ""
			(at 224.79 149.86 0)
			(effects
				(font
					(size 1.27 1.27)
				)
				(hide yes)
			)
		)
		(property "Author" "Antmicro"
			(at 233.68 157.48 0)
			(effects
				(font
					(size 1.27 1.27)
					(thickness 0.15)
				)
				(justify left bottom)
				(hide yes)
			)
		)
		(property "License" "Apache-2.0"
			(at 233.68 160.02 0)
			(effects
				(font
					(size 1.27 1.27)
					(thickness 0.15)
				)
				(justify left bottom)
				(hide yes)
			)
		)
		(pin "1"
		)
		(instances
			(project "oculink-to-10gbe-adapter"
				(path ""
					(reference "#PWR0348")
					(unit 1)
				)
			)
			(project "thunderbolt-to-10gbe-adapter"
				(path ""
					(reference "#PWR0460")
					(unit 1)
				)
			)
		)
	)
	(symbol
		(lib_id "antmicropower:+5V")
		(at 176.53 162.56 0)
		(unit 1)
		(exclude_from_sim no)
		(in_bom yes)
		(on_board yes)
		(dnp no)
		(fields_autoplaced yes)
		(property "Reference" "#PWR0455"
			(at 191.77 165.1 0)
			(effects
				(font
					(size 1.27 1.27)
					(thickness 0.15)
				)
				(justify left bottom)
				(hide yes)
			)
		)
		(property "Value" "+5V"
			(at 176.53 157.48 0)
			(effects
				(font
					(size 1.27 1.27)
					(thickness 0.15)
				)
			)
		)
		(property "Footprint" ""
			(at 191.77 170.18 0)
			(effects
				(font
					(size 1.27 1.27)
					(thickness 0.15)
				)
				(justify left bottom)
				(hide yes)
			)
		)
		(property "Datasheet" ""
			(at 191.77 172.72 0)
			(effects
				(font
					(size 1.27 1.27)
					(thickness 0.15)
				)
				(justify left bottom)
				(hide yes)
			)
		)
		(property "Description" ""
			(at 191.77 175.26 0)
			(effects
				(font
					(size 1.27 1.27)
				)
				(justify left bottom)
				(hide yes)
			)
		)
		(property "Author" "Antmicro"
			(at 191.77 170.18 0)
			(effects
				(font
					(size 1.27 1.27)
					(thickness 0.15)
				)
				(justify left bottom)
				(hide yes)
			)
		)
		(property "License" "Apache-2.0"
			(at 191.77 172.72 0)
			(effects
				(font
					(size 1.27 1.27)
					(thickness 0.15)
				)
				(justify left bottom)
				(hide yes)
			)
		)
		(pin "1"
		)
		(instances
			(project "thunderbolt-to-10gbe-adapter"
				(path ""
					(reference "#PWR0455")
					(unit 1)
				)
			)
		)
	)
	(symbol
		(lib_id "antmicroResistors0402:R_10k_0402")
		(at 224.79 147.32 90)
		(unit 1)
		(exclude_from_sim no)
		(in_bom yes)
		(on_board yes)
		(dnp no)
		(property "Reference" "R222"
			(at 226.06 143.51 90)
			(effects
				(font
					(size 1.27 1.27)
					(thickness 0.15)
				)
				(justify right)
			)
		)
		(property "Value" "R_10k_0402"
			(at 237.49 127 0)
			(effects
				(font
					(size 1.27 1.27)
					(thickness 0.15)
				)
				(justify left bottom)
				(hide yes)
			)
		)
		(property "Footprint" "antmicro-footprints:R_0402_1005Metric"
			(at 240.03 127 0)
			(effects
				(font
					(size 1.27 1.27)
					(thickness 0.15)
				)
				(justify left bottom)
				(hide yes)
			)
		)
		(property "Datasheet" "https://www.bourns.com/docs/product-datasheets/cr.pdf"
			(at 242.57 127 0)
			(effects
				(font
					(size 1.27 1.27)
					(thickness 0.15)
				)
				(justify left bottom)
				(hide yes)
			)
		)
		(property "Description" "SMD Chip Resistor, 10 kohm, ± 1%, 62.5 mW, 0402 [1005 Metric], Thick Film, General Purpose"
			(at 255.27 127 0)
			(effects
				(font
					(size 1.27 1.27)
				)
				(justify left bottom)
				(hide yes)
			)
		)
		(property "MPN" "CR0402-FX-1002GLF"
			(at 245.11 127 0)
			(effects
				(font
					(size 1.27 1.27)
					(thickness 0.15)
				)
				(justify left bottom)
				(hide yes)
			)
		)
		(property "Manufacturer" "Bourns"
			(at 247.65 127 0)
			(effects
				(font
					(size 1.27 1.27)
					(thickness 0.15)
				)
				(justify left bottom)
				(hide yes)
			)
		)
		(property "License" "Apache-2.0"
			(at 250.19 127 0)
			(effects
				(font
					(size 1.27 1.27)
					(thickness 0.15)
				)
				(justify left bottom)
				(hide yes)
			)
		)
		(property "Author" "Antmicro"
			(at 252.73 127 0)
			(effects
				(font
					(size 1.27 1.27)
					(thickness 0.15)
				)
				(justify left bottom)
				(hide yes)
			)
		)
		(property "Val" "10k"
			(at 226.06 146.05 90)
			(effects
				(font
					(size 1.27 1.27)
					(thickness 0.15)
				)
				(justify right)
			)
		)
		(property "Tolerance" "1%"
			(at 234.95 127 0)
			(effects
				(font
					(size 1.27 1.27)
				)
				(justify left bottom)
				(hide yes)
			)
		)
		(pin "2"
		)
		(pin "1"
		)
		(instances
			(project "oculink-to-10gbe-adapter"
				(path ""
					(reference "R180")
					(unit 1)
				)
			)
			(project "thunderbolt-to-10gbe-adapter"
				(path ""
					(reference "R222")
					(unit 1)
				)
			)
		)
	)
	(symbol
		(lib_id "antmicroCapacitors0402:C_470p_0402")
		(at 237.49 147.32 90)
		(unit 1)
		(exclude_from_sim no)
		(in_bom yes)
		(on_board yes)
		(dnp no)
		(fields_autoplaced yes)
		(property "Reference" "C309"
			(at 240.03 143.5036 90)
			(effects
				(font
					(size 1.27 1.27)
					(thickness 0.15)
				)
				(justify right)
			)
		)
		(property "Value" "C_470p_0402"
			(at 247.65 127 0)
			(effects
				(font
					(size 1.27 1.27)
					(thickness 0.15)
				)
				(justify left bottom)
				(hide yes)
			)
		)
		(property "Footprint" "antmicro-footprints:C_0402_1005Metric"
			(at 250.19 127 0)
			(effects
				(font
					(size 1.27 1.27)
					(thickness 0.15)
				)
				(justify left bottom)
				(hide yes)
			)
		)
		(property "Datasheet" "https://www.passivecomponent.com/wp-content/uploads/datasheet/WTC_MLCC_General_Purpose.pdf"
			(at 252.73 127 0)
			(effects
				(font
					(size 1.27 1.27)
					(thickness 0.15)
				)
				(justify left bottom)
				(hide yes)
			)
		)
		(property "Description" "SMD Multilayer Ceramic Capacitor, General Purpose, 470 pF, 25 V, 0402 [1005 Metric], ± 10%, X7R"
			(at 270.51 127 0)
			(effects
				(font
					(size 1.27 1.27)
				)
				(justify left bottom)
				(hide yes)
			)
		)
		(property "MPN" "0402B471K250CT"
			(at 255.27 127 0)
			(effects
				(font
					(size 1.27 1.27)
					(thickness 0.15)
				)
				(justify left bottom)
				(hide yes)
			)
		)
		(property "Manufacturer" "Walsin"
			(at 257.81 127 0)
			(effects
				(font
					(size 1.27 1.27)
					(thickness 0.15)
				)
				(justify left bottom)
				(hide yes)
			)
		)
		(property "License" "Apache-2.0"
			(at 260.35 127 0)
			(effects
				(font
					(size 1.27 1.27)
					(thickness 0.15)
				)
				(justify left bottom)
				(hide yes)
			)
		)
		(property "Author" "Antmicro"
			(at 262.89 127 0)
			(effects
				(font
					(size 1.27 1.27)
					(thickness 0.15)
				)
				(justify left bottom)
				(hide yes)
			)
		)
		(property "Val" "470p"
			(at 240.03 146.0436 90)
			(effects
				(font
					(size 1.27 1.27)
					(thickness 0.15)
				)
				(justify right)
			)
		)
		(property "Voltage" "25V"
			(at 265.43 127 0)
			(effects
				(font
					(size 1.27 1.27)
				)
				(justify left bottom)
				(hide yes)
			)
		)
		(property "Dielectric" "X7R"
			(at 267.97 127 0)
			(effects
				(font
					(size 1.27 1.27)
				)
				(justify left bottom)
				(hide yes)
			)
		)
		(pin "2"
		)
		(pin "1"
		)
		(instances
			(project ""
				(path ""
					(reference "C213")
					(unit 1)
				)
			)
			(project "thunderbolt-to-10gbe-adapter"
				(path ""
					(reference "C309")
					(unit 1)
				)
			)
		)
	)
	(symbol
		(lib_id "antmicropower:GND")
		(at 193.04 184.15 0)
		(unit 1)
		(exclude_from_sim no)
		(in_bom yes)
		(on_board yes)
		(dnp no)
		(property "Reference" "#PWR0458"
			(at 201.93 186.69 0)
			(effects
				(font
					(size 1.27 1.27)
					(thickness 0.15)
				)
				(justify left bottom)
				(hide yes)
			)
		)
		(property "Value" "GND"
			(at 193.04 187.96 0)
			(effects
				(font
					(size 1.27 1.27)
					(thickness 0.15)
				)
			)
		)
		(property "Footprint" ""
			(at 201.93 191.77 0)
			(effects
				(font
					(size 1.27 1.27)
					(thickness 0.15)
				)
				(justify left bottom)
				(hide yes)
			)
		)
		(property "Datasheet" ""
			(at 201.93 196.85 0)
			(effects
				(font
					(size 1.27 1.27)
					(thickness 0.15)
				)
				(justify left bottom)
				(hide yes)
			)
		)
		(property "Description" ""
			(at 193.04 184.15 0)
			(effects
				(font
					(size 1.27 1.27)
				)
				(hide yes)
			)
		)
		(property "Author" "Antmicro"
			(at 201.93 191.77 0)
			(effects
				(font
					(size 1.27 1.27)
					(thickness 0.15)
				)
				(justify left bottom)
				(hide yes)
			)
		)
		(property "License" "Apache-2.0"
			(at 201.93 194.31 0)
			(effects
				(font
					(size 1.27 1.27)
					(thickness 0.15)
				)
				(justify left bottom)
				(hide yes)
			)
		)
		(pin "1"
		)
		(instances
			(project "oculink-to-10gbe-adapter"
				(path ""
					(reference "#PWR0344")
					(unit 1)
				)
			)
			(project "thunderbolt-to-10gbe-adapter"
				(path ""
					(reference "#PWR0458")
					(unit 1)
				)
			)
		)
	)
	(symbol
		(lib_id "antmicropower:GND")
		(at 172.72 147.32 0)
		(unit 1)
		(exclude_from_sim no)
		(in_bom yes)
		(on_board yes)
		(dnp no)
		(property "Reference" "#PWR0454"
			(at 181.61 149.86 0)
			(effects
				(font
					(size 1.27 1.27)
					(thickness 0.15)
				)
				(justify left bottom)
				(hide yes)
			)
		)
		(property "Value" "GND"
			(at 172.72 151.13 0)
			(effects
				(font
					(size 1.27 1.27)
					(thickness 0.15)
				)
			)
		)
		(property "Footprint" ""
			(at 181.61 154.94 0)
			(effects
				(font
					(size 1.27 1.27)
					(thickness 0.15)
				)
				(justify left bottom)
				(hide yes)
			)
		)
		(property "Datasheet" ""
			(at 181.61 160.02 0)
			(effects
				(font
					(size 1.27 1.27)
					(thickness 0.15)
				)
				(justify left bottom)
				(hide yes)
			)
		)
		(property "Description" ""
			(at 172.72 147.32 0)
			(effects
				(font
					(size 1.27 1.27)
				)
				(hide yes)
			)
		)
		(property "Author" "Antmicro"
			(at 181.61 154.94 0)
			(effects
				(font
					(size 1.27 1.27)
					(thickness 0.15)
				)
				(justify left bottom)
				(hide yes)
			)
		)
		(property "License" "Apache-2.0"
			(at 181.61 157.48 0)
			(effects
				(font
					(size 1.27 1.27)
					(thickness 0.15)
				)
				(justify left bottom)
				(hide yes)
			)
		)
		(pin "1"
		)
		(instances
			(project "oculink-to-10gbe-adapter"
				(path ""
					(reference "#PWR0342")
					(unit 1)
				)
			)
			(project "thunderbolt-to-10gbe-adapter"
				(path ""
					(reference "#PWR0454")
					(unit 1)
				)
			)
		)
	)
	(symbol
		(lib_id "antmicroCapacitors0402:C_100n_0402")
		(at 182.88 129.54 90)
		(unit 1)
		(exclude_from_sim no)
		(in_bom yes)
		(on_board yes)
		(dnp no)
		(property "Reference" "C74"
			(at 180.34 125.7236 90)
			(effects
				(font
					(size 1.27 1.27)
					(thickness 0.15)
				)
				(justify left)
			)
		)
		(property "Value" "C_100n_0402"
			(at 193.04 109.22 0)
			(effects
				(font
					(size 1.27 1.27)
					(thickness 0.15)
				)
				(justify left bottom)
				(hide yes)
			)
		)
		(property "Footprint" "antmicro-footprints:C_0402_1005Metric"
			(at 195.58 109.22 0)
			(effects
				(font
					(size 1.27 1.27)
					(thickness 0.15)
				)
				(justify left bottom)
				(hide yes)
			)
		)
		(property "Datasheet" "https://www.murata.com/products/productdetail?partno=GRM155R61H104KE14%23"
			(at 198.12 109.22 0)
			(effects
				(font
					(size 1.27 1.27)
					(thickness 0.15)
				)
				(justify left bottom)
				(hide yes)
			)
		)
		(property "Description" "SMD Multilayer Ceramic Capacitor, 0.1 µF, 50 V, 0402 [1005 Metric], ± 10%, X5R, GRM Series"
			(at 215.9 109.22 0)
			(effects
				(font
					(size 1.27 1.27)
				)
				(justify left bottom)
				(hide yes)
			)
		)
		(property "MPN" "GRM155R61H104KE14D"
			(at 200.66 109.22 0)
			(effects
				(font
					(size 1.27 1.27)
					(thickness 0.15)
				)
				(justify left bottom)
				(hide yes)
			)
		)
		(property "Manufacturer" "Murata"
			(at 203.2 109.22 0)
			(effects
				(font
					(size 1.27 1.27)
					(thickness 0.15)
				)
				(justify left bottom)
				(hide yes)
			)
		)
		(property "License" "Apache-2.0"
			(at 205.74 109.22 0)
			(effects
				(font
					(size 1.27 1.27)
					(thickness 0.15)
				)
				(justify left bottom)
				(hide yes)
			)
		)
		(property "Author" "Antmicro"
			(at 208.28 109.22 0)
			(effects
				(font
					(size 1.27 1.27)
					(thickness 0.15)
				)
				(justify left bottom)
				(hide yes)
			)
		)
		(property "Val" "100n"
			(at 180.34 128.2636 90)
			(effects
				(font
					(size 1.27 1.27)
					(thickness 0.15)
				)
				(justify left)
			)
		)
		(property "Voltage" "50V"
			(at 210.82 109.22 0)
			(effects
				(font
					(size 1.27 1.27)
				)
				(justify left bottom)
				(hide yes)
			)
		)
		(property "Dielectric" "X5R"
			(at 213.36 109.22 0)
			(effects
				(font
					(size 1.27 1.27)
				)
				(justify left bottom)
				(hide yes)
			)
		)
		(pin "2"
		)
		(pin "1"
		)
		(instances
			(project "thunderbolt-to-10gbe-adapter"
				(path ""
					(reference "C74")
					(unit 1)
				)
			)
		)
	)
	(symbol
		(lib_id "antmicropower:GND")
		(at 182.88 129.54 0)
		(unit 1)
		(exclude_from_sim no)
		(in_bom yes)
		(on_board yes)
		(dnp no)
		(property "Reference" "#PWR0107"
			(at 191.77 132.08 0)
			(effects
				(font
					(size 1.27 1.27)
					(thickness 0.15)
				)
				(justify left bottom)
				(hide yes)
			)
		)
		(property "Value" "GND"
			(at 182.88 133.35 0)
			(effects
				(font
					(size 1.27 1.27)
					(thickness 0.15)
				)
			)
		)
		(property "Footprint" ""
			(at 191.77 137.16 0)
			(effects
				(font
					(size 1.27 1.27)
					(thickness 0.15)
				)
				(justify left bottom)
				(hide yes)
			)
		)
		(property "Datasheet" ""
			(at 191.77 142.24 0)
			(effects
				(font
					(size 1.27 1.27)
					(thickness 0.15)
				)
				(justify left bottom)
				(hide yes)
			)
		)
		(property "Description" ""
			(at 182.88 129.54 0)
			(effects
				(font
					(size 1.27 1.27)
				)
				(hide yes)
			)
		)
		(property "Author" "Antmicro"
			(at 191.77 137.16 0)
			(effects
				(font
					(size 1.27 1.27)
					(thickness 0.15)
				)
				(justify left bottom)
				(hide yes)
			)
		)
		(property "License" "Apache-2.0"
			(at 191.77 139.7 0)
			(effects
				(font
					(size 1.27 1.27)
					(thickness 0.15)
				)
				(justify left bottom)
				(hide yes)
			)
		)
		(pin "1"
		)
		(instances
			(project "thunderbolt-to-10gbe-adapter"
				(path ""
					(reference "#PWR0107")
					(unit 1)
				)
			)
		)
	)
	(symbol
		(lib_id "antmicroTVSDiodes:PESD5Z5_0F")
		(at 317.5 133.35 90)
		(mirror x)
		(unit 1)
		(exclude_from_sim no)
		(in_bom yes)
		(on_board yes)
		(dnp no)
		(property "Reference" "D12"
			(at 314.96 134.62 90)
			(effects
				(font
					(size 1.27 1.27)
					(thickness 0.15)
				)
				(justify left)
			)
		)
		(property "Value" "PESD5Z5_0F"
			(at 330.2 148.59 0)
			(effects
				(font
					(size 1.27 1.27)
					(thickness 0.15)
				)
				(justify left bottom)
				(hide yes)
			)
		)
		(property "Footprint" "antmicro-footprints:SOD-523"
			(at 322.58 148.59 0)
			(effects
				(font
					(size 1.27 1.27)
					(thickness 0.15)
				)
				(justify left bottom)
				(hide yes)
			)
		)
		(property "Datasheet" "https://assets.nexperia.com/documents/data-sheet/PESD5Z5_0.pdf"
			(at 325.12 148.59 0)
			(effects
				(font
					(size 1.27 1.27)
					(thickness 0.15)
				)
				(justify left bottom)
				(hide yes)
			)
		)
		(property "Description" "Unidirectional TVS, 30 kV,  SOD-523, 5 V, 89 pF"
			(at 337.82 148.59 0)
			(effects
				(font
					(size 1.27 1.27)
				)
				(justify left bottom)
				(hide yes)
			)
		)
		(property "Manufacturer" "Nexperia"
			(at 327.66 148.59 0)
			(effects
				(font
					(size 1.27 1.27)
					(thickness 0.15)
				)
				(justify left bottom)
				(hide yes)
			)
		)
		(property "MPN" "PESD5Z5.0F"
			(at 314.96 137.16 90)
			(effects
				(font
					(size 1.27 1.27)
					(thickness 0.15)
				)
				(justify left)
			)
		)
		(property "Author" "Antmicro"
			(at 332.74 148.59 0)
			(effects
				(font
					(size 1.27 1.27)
					(thickness 0.15)
				)
				(justify left bottom)
				(hide yes)
			)
		)
		(property "License" "Apache-2.0"
			(at 335.28 148.59 0)
			(effects
				(font
					(size 1.27 1.27)
					(thickness 0.15)
				)
				(justify left bottom)
				(hide yes)
			)
		)
		(pin "2"
		)
		(pin "1"
		)
		(instances
			(project "oculink-to-10gbe-adapter"
				(path ""
					(reference "D13")
					(unit 1)
				)
			)
			(project "thunderbolt-to-10gbe-adapter"
				(path ""
					(reference "D12")
					(unit 1)
				)
			)
		)
	)
	(symbol
		(lib_id "antmicropower:GND")
		(at 317.5 157.48 0)
		(mirror y)
		(unit 1)
		(exclude_from_sim no)
		(in_bom yes)
		(on_board yes)
		(dnp no)
		(property "Reference" "#PWR0465"
			(at 308.61 160.02 0)
			(effects
				(font
					(size 1.27 1.27)
					(thickness 0.15)
				)
				(justify left bottom)
				(hide yes)
			)
		)
		(property "Value" "GND"
			(at 317.5 161.29 0)
			(effects
				(font
					(size 1.27 1.27)
					(thickness 0.15)
				)
			)
		)
		(property "Footprint" ""
			(at 308.61 165.1 0)
			(effects
				(font
					(size 1.27 1.27)
					(thickness 0.15)
				)
				(justify left bottom)
				(hide yes)
			)
		)
		(property "Datasheet" ""
			(at 308.61 170.18 0)
			(effects
				(font
					(size 1.27 1.27)
					(thickness 0.15)
				)
				(justify left bottom)
				(hide yes)
			)
		)
		(property "Description" ""
			(at 317.5 157.48 0)
			(effects
				(font
					(size 1.27 1.27)
				)
				(hide yes)
			)
		)
		(property "Author" "Antmicro"
			(at 308.61 165.1 0)
			(effects
				(font
					(size 1.27 1.27)
					(thickness 0.15)
				)
				(justify left bottom)
				(hide yes)
			)
		)
		(property "License" "Apache-2.0"
			(at 308.61 167.64 0)
			(effects
				(font
					(size 1.27 1.27)
					(thickness 0.15)
				)
				(justify left bottom)
				(hide yes)
			)
		)
		(pin "1"
		)
		(instances
			(project "oculink-to-10gbe-adapter"
				(path ""
					(reference "#PWR0303")
					(unit 1)
				)
			)
			(project "thunderbolt-to-10gbe-adapter"
				(path ""
					(reference "#PWR0465")
					(unit 1)
				)
			)
		)
	)
	(symbol
		(lib_id "antmicroTemperatureSensorsAnalogandDigitalOutput:RT_NTC_10k_0402")
		(at 153.67 139.7 270)
		(unit 1)
		(exclude_from_sim no)
		(in_bom yes)
		(on_board yes)
		(dnp no)
		(fields_autoplaced yes)
		(property "Reference" "RT1"
			(at 156.21 140.9065 90)
			(effects
				(font
					(size 1.27 1.27)
					(thickness 0.15)
				)
				(justify left)
			)
		)
		(property "Value" "RT_NTC_10k_0402"
			(at 143.51 160.02 0)
			(effects
				(font
					(size 1.27 1.27)
					(thickness 0.15)
				)
				(justify left bottom)
				(hide yes)
			)
		)
		(property "Footprint" "antmicro-footprints:R_0402_1005Metric"
			(at 138.43 160.02 0)
			(effects
				(font
					(size 1.27 1.27)
					(thickness 0.15)
				)
				(justify left bottom)
				(hide yes)
			)
		)
		(property "Datasheet" "https://eu.mouser.com/datasheet/2/281/r44e-522712.pdf"
			(at 135.89 160.02 0)
			(effects
				(font
					(size 1.27 1.27)
					(thickness 0.15)
				)
				(justify left bottom)
				(hide yes)
			)
		)
		(property "Description" "10k NTC in 0402 package with 5V max voltage"
			(at 123.19 160.02 0)
			(effects
				(font
					(size 1.27 1.27)
				)
				(justify left bottom)
				(hide yes)
			)
		)
		(property "MPN" "NCP15XH103F03RC"
			(at 130.81 160.02 0)
			(effects
				(font
					(size 1.27 1.27)
				)
				(justify left bottom)
				(hide yes)
			)
		)
		(property "Manufacturer" "Murata"
			(at 133.35 160.02 0)
			(effects
				(font
					(size 1.27 1.27)
				)
				(justify left bottom)
				(hide yes)
			)
		)
		(property "License" "Apache-2.0"
			(at 125.73 160.02 0)
			(effects
				(font
					(size 1.27 1.27)
				)
				(justify left bottom)
				(hide yes)
			)
		)
		(property "Author" "Antmicro"
			(at 128.27 160.02 0)
			(effects
				(font
					(size 1.27 1.27)
				)
				(justify left bottom)
				(hide yes)
			)
		)
		(property "Val" "10k"
			(at 156.21 143.4464 90)
			(effects
				(font
					(size 1.27 1.27)
				)
				(justify left)
			)
		)
		(property "Voltage" "5V"
			(at 140.97 160.02 0)
			(effects
				(font
					(size 1.27 1.27)
				)
				(justify left bottom)
				(hide yes)
			)
		)
		(pin "1"
		)
		(pin "2"
		)
		(instances
			(project ""
				(path ""
					(reference "RT1")
					(unit 1)
				)
			)
			(project "thunderbolt-to-10gbe-adapter"
				(path ""
					(reference "RT1")
					(unit 1)
				)
			)
		)
	)
	(symbol
		(lib_id "antmicropower:GND")
		(at 279.4 149.86 0)
		(unit 1)
		(exclude_from_sim no)
		(in_bom yes)
		(on_board yes)
		(dnp no)
		(property "Reference" "#PWR0463"
			(at 288.29 152.4 0)
			(effects
				(font
					(size 1.27 1.27)
					(thickness 0.15)
				)
				(justify left bottom)
				(hide yes)
			)
		)
		(property "Value" "GND"
			(at 279.4 153.67 0)
			(effects
				(font
					(size 1.27 1.27)
					(thickness 0.15)
				)
			)
		)
		(property "Footprint" ""
			(at 288.29 157.48 0)
			(effects
				(font
					(size 1.27 1.27)
					(thickness 0.15)
				)
				(justify left bottom)
				(hide yes)
			)
		)
		(property "Datasheet" ""
			(at 288.29 162.56 0)
			(effects
				(font
					(size 1.27 1.27)
					(thickness 0.15)
				)
				(justify left bottom)
				(hide yes)
			)
		)
		(property "Description" ""
			(at 279.4 149.86 0)
			(effects
				(font
					(size 1.27 1.27)
				)
				(hide yes)
			)
		)
		(property "Author" "Antmicro"
			(at 288.29 157.48 0)
			(effects
				(font
					(size 1.27 1.27)
					(thickness 0.15)
				)
				(justify left bottom)
				(hide yes)
			)
		)
		(property "License" "Apache-2.0"
			(at 288.29 160.02 0)
			(effects
				(font
					(size 1.27 1.27)
					(thickness 0.15)
				)
				(justify left bottom)
				(hide yes)
			)
		)
		(pin "1"
		)
		(instances
			(project "oculink-to-10gbe-adapter"
				(path ""
					(reference "#PWR0340")
					(unit 1)
				)
			)
			(project "thunderbolt-to-10gbe-adapter"
				(path ""
					(reference "#PWR0463")
					(unit 1)
				)
			)
		)
	)
	(symbol
		(lib_id "antmicropower:GND")
		(at 317.5 140.97 0)
		(unit 1)
		(exclude_from_sim no)
		(in_bom yes)
		(on_board yes)
		(dnp no)
		(property "Reference" "#PWR0464"
			(at 326.39 143.51 0)
			(effects
				(font
					(size 1.27 1.27)
					(thickness 0.15)
				)
				(justify left bottom)
				(hide yes)
			)
		)
		(property "Value" "GND"
			(at 317.5 144.78 0)
			(effects
				(font
					(size 1.27 1.27)
					(thickness 0.15)
				)
			)
		)
		(property "Footprint" ""
			(at 326.39 148.59 0)
			(effects
				(font
					(size 1.27 1.27)
					(thickness 0.15)
				)
				(justify left bottom)
				(hide yes)
			)
		)
		(property "Datasheet" ""
			(at 326.39 153.67 0)
			(effects
				(font
					(size 1.27 1.27)
					(thickness 0.15)
				)
				(justify left bottom)
				(hide yes)
			)
		)
		(property "Description" ""
			(at 317.5 140.97 0)
			(effects
				(font
					(size 1.27 1.27)
				)
				(hide yes)
			)
		)
		(property "Author" "Antmicro"
			(at 326.39 148.59 0)
			(effects
				(font
					(size 1.27 1.27)
					(thickness 0.15)
				)
				(justify left bottom)
				(hide yes)
			)
		)
		(property "License" "Apache-2.0"
			(at 326.39 151.13 0)
			(effects
				(font
					(size 1.27 1.27)
					(thickness 0.15)
				)
				(justify left bottom)
				(hide yes)
			)
		)
		(pin "1"
		)
		(instances
			(project "oculink-to-10gbe-adapter"
				(path ""
					(reference "#PWR0302")
					(unit 1)
				)
			)
			(project "thunderbolt-to-10gbe-adapter"
				(path ""
					(reference "#PWR0464")
					(unit 1)
				)
			)
		)
	)
	(symbol
		(lib_id "antmicroCapacitors0402:C_1u_0402")
		(at 172.72 144.78 90)
		(unit 1)
		(exclude_from_sim no)
		(in_bom yes)
		(on_board yes)
		(dnp no)
		(fields_autoplaced yes)
		(property "Reference" "C308"
			(at 175.26 140.9636 90)
			(effects
				(font
					(size 1.27 1.27)
					(thickness 0.15)
				)
				(justify right)
			)
		)
		(property "Value" "C_1u_0402"
			(at 182.88 124.46 0)
			(effects
				(font
					(size 1.27 1.27)
					(thickness 0.15)
				)
				(justify left bottom)
				(hide yes)
			)
		)
		(property "Footprint" "antmicro-footprints:C_0402_1005Metric"
			(at 185.42 124.46 0)
			(effects
				(font
					(size 1.27 1.27)
					(thickness 0.15)
				)
				(justify left bottom)
				(hide yes)
			)
		)
		(property "Datasheet" "https://product.tdk.com/en/search/capacitor/ceramic/mlcc/info?part_no=C1005X6S1A105K050BC"
			(at 187.96 124.46 0)
			(effects
				(font
					(size 1.27 1.27)
					(thickness 0.15)
				)
				(justify left bottom)
				(hide yes)
			)
		)
		(property "Description" "SMD Multilayer Ceramic Capacitor, 1 µF, 10 V, 0402 [1005 Metric], ± 10%, X6S, C"
			(at 205.74 124.46 0)
			(effects
				(font
					(size 1.27 1.27)
				)
				(justify left bottom)
				(hide yes)
			)
		)
		(property "MPN" "C1005X6S1A105K050BC"
			(at 190.5 124.46 0)
			(effects
				(font
					(size 1.27 1.27)
					(thickness 0.15)
				)
				(justify left bottom)
				(hide yes)
			)
		)
		(property "Manufacturer" "TDK"
			(at 193.04 124.46 0)
			(effects
				(font
					(size 1.27 1.27)
					(thickness 0.15)
				)
				(justify left bottom)
				(hide yes)
			)
		)
		(property "License" "Apache-2.0"
			(at 195.58 124.46 0)
			(effects
				(font
					(size 1.27 1.27)
					(thickness 0.15)
				)
				(justify left bottom)
				(hide yes)
			)
		)
		(property "Author" "Antmicro"
			(at 198.12 124.46 0)
			(effects
				(font
					(size 1.27 1.27)
					(thickness 0.15)
				)
				(justify left bottom)
				(hide yes)
			)
		)
		(property "Val" "1u"
			(at 175.26 143.5036 90)
			(effects
				(font
					(size 1.27 1.27)
					(thickness 0.15)
				)
				(justify right)
			)
		)
		(property "Voltage" ""
			(at 200.66 124.46 0)
			(effects
				(font
					(size 1.27 1.27)
				)
				(justify left bottom)
				(hide yes)
			)
		)
		(property "Dielectric" ""
			(at 203.2 124.46 0)
			(effects
				(font
					(size 1.27 1.27)
				)
				(justify left bottom)
				(hide yes)
			)
		)
		(pin "1"
		)
		(pin "2"
		)
		(instances
			(project ""
				(path ""
					(reference "C209")
					(unit 1)
				)
			)
			(project "thunderbolt-to-10gbe-adapter"
				(path ""
					(reference "C308")
					(unit 1)
				)
			)
		)
	)
	(symbol
		(lib_id "antmicroResistors0402:R_0R_0402")
		(at 193.04 181.61 90)
		(unit 1)
		(exclude_from_sim no)
		(in_bom yes)
		(on_board yes)
		(dnp no)
		(property "Reference" "R221"
			(at 194.31 177.8 90)
			(effects
				(font
					(size 1.27 1.27)
					(thickness 0.15)
				)
				(justify right)
			)
		)
		(property "Value" "R_0R_0402"
			(at 205.74 161.29 0)
			(effects
				(font
					(size 1.27 1.27)
					(thickness 0.15)
				)
				(justify left bottom)
				(hide yes)
			)
		)
		(property "Footprint" "antmicro-footprints:R_0402_1005Metric"
			(at 208.28 161.29 0)
			(effects
				(font
					(size 1.27 1.27)
					(thickness 0.15)
				)
				(justify left bottom)
				(hide yes)
			)
		)
		(property "Datasheet" "https://industrial.panasonic.com/cdbs/www-data/pdf/RDA0000/AOA0000C301.pdf"
			(at 210.82 161.29 0)
			(effects
				(font
					(size 1.27 1.27)
					(thickness 0.15)
				)
				(justify left bottom)
				(hide yes)
			)
		)
		(property "Description" "SMD Chip Resistor, Jumper, 0 ohm, 100 mW, 0402 [1005 Metric], Thick Film, General Purpose"
			(at 226.06 161.29 0)
			(effects
				(font
					(size 1.27 1.27)
				)
				(justify left bottom)
				(hide yes)
			)
		)
		(property "MPN" "ERJ2GE0R00X"
			(at 213.36 161.29 0)
			(effects
				(font
					(size 1.27 1.27)
					(thickness 0.15)
				)
				(justify left bottom)
				(hide yes)
			)
		)
		(property "Manufacturer" "Panasonic"
			(at 215.9 161.29 0)
			(effects
				(font
					(size 1.27 1.27)
					(thickness 0.15)
				)
				(justify left bottom)
				(hide yes)
			)
		)
		(property "License" "Apache-2.0"
			(at 218.44 161.29 0)
			(effects
				(font
					(size 1.27 1.27)
					(thickness 0.15)
				)
				(justify left bottom)
				(hide yes)
			)
		)
		(property "Author" "Antmicro"
			(at 220.98 161.29 0)
			(effects
				(font
					(size 1.27 1.27)
					(thickness 0.15)
				)
				(justify left bottom)
				(hide yes)
			)
		)
		(property "Val" "0R"
			(at 194.31 180.34 90)
			(effects
				(font
					(size 1.27 1.27)
					(thickness 0.15)
				)
				(justify right)
			)
		)
		(property "Tolerance" "~"
			(at 203.2 161.29 0)
			(effects
				(font
					(size 1.27 1.27)
				)
				(justify left bottom)
				(hide yes)
			)
		)
		(property "Current" "1A"
			(at 223.52 161.29 0)
			(effects
				(font
					(size 1.27 1.27)
					(thickness 0.15)
				)
				(justify left bottom)
				(hide yes)
			)
		)
		(pin "2"
		)
		(pin "1"
		)
		(instances
			(project ""
				(path ""
					(reference "R176")
					(unit 1)
				)
			)
			(project "thunderbolt-to-10gbe-adapter"
				(path ""
					(reference "R221")
					(unit 1)
				)
			)
		)
	)
	(symbol
		(lib_id "antmicropower:+5V")
		(at 153.67 121.92 0)
		(unit 1)
		(exclude_from_sim no)
		(in_bom yes)
		(on_board yes)
		(dnp no)
		(fields_autoplaced yes)
		(property "Reference" "#PWR0452"
			(at 168.91 124.46 0)
			(effects
				(font
					(size 1.27 1.27)
					(thickness 0.15)
				)
				(justify left bottom)
				(hide yes)
			)
		)
		(property "Value" "+5V"
			(at 153.67 116.84 0)
			(effects
				(font
					(size 1.27 1.27)
					(thickness 0.15)
				)
			)
		)
		(property "Footprint" ""
			(at 168.91 129.54 0)
			(effects
				(font
					(size 1.27 1.27)
					(thickness 0.15)
				)
				(justify left bottom)
				(hide yes)
			)
		)
		(property "Datasheet" ""
			(at 168.91 132.08 0)
			(effects
				(font
					(size 1.27 1.27)
					(thickness 0.15)
				)
				(justify left bottom)
				(hide yes)
			)
		)
		(property "Description" ""
			(at 168.91 134.62 0)
			(effects
				(font
					(size 1.27 1.27)
				)
				(justify left bottom)
				(hide yes)
			)
		)
		(property "Author" "Antmicro"
			(at 168.91 129.54 0)
			(effects
				(font
					(size 1.27 1.27)
					(thickness 0.15)
				)
				(justify left bottom)
				(hide yes)
			)
		)
		(property "License" "Apache-2.0"
			(at 168.91 132.08 0)
			(effects
				(font
					(size 1.27 1.27)
					(thickness 0.15)
				)
				(justify left bottom)
				(hide yes)
			)
		)
		(pin "1"
		)
		(instances
			(project "thunderbolt-to-10gbe-adapter"
				(path ""
					(reference "#PWR0452")
					(unit 1)
				)
			)
		)
	)
	(symbol
		(lib_id "antmicroResistors0402:R_6k04_0.1%_0402")
		(at 153.67 132.08 90)
		(unit 1)
		(exclude_from_sim no)
		(in_bom yes)
		(on_board yes)
		(dnp no)
		(fields_autoplaced yes)
		(property "Reference" "R216"
			(at 156.21 127 90)
			(effects
				(font
					(size 1.27 1.27)
					(thickness 0.15)
				)
				(justify right)
			)
		)
		(property "Value" "R_6k04_0.1%_0402"
			(at 166.37 111.76 0)
			(effects
				(font
					(size 1.27 1.27)
					(thickness 0.15)
				)
				(justify left bottom)
				(hide yes)
			)
		)
		(property "Footprint" "antmicro-footprints:R_0402_1005Metric"
			(at 168.91 111.76 0)
			(effects
				(font
					(size 1.27 1.27)
					(thickness 0.15)
				)
				(justify left bottom)
				(hide yes)
			)
		)
		(property "Datasheet" "https://www.vishay.com/docs/28758/tnpw_e3.pdf"
			(at 171.45 111.76 0)
			(effects
				(font
					(size 1.27 1.27)
					(thickness 0.15)
				)
				(justify left bottom)
				(hide yes)
			)
		)
		(property "Description" "SMD Chip Resistor, 6.49 kohm, ± 1%, 62.5 mW, 0402 [1005 Metric], Thick Film, General Purpose"
			(at 184.15 111.76 0)
			(effects
				(font
					(size 1.27 1.27)
				)
				(justify left bottom)
				(hide yes)
			)
		)
		(property "MPN" "TNPW04026K04BEED"
			(at 173.99 111.76 0)
			(effects
				(font
					(size 1.27 1.27)
					(thickness 0.15)
				)
				(justify left bottom)
				(hide yes)
			)
		)
		(property "Manufacturer" "Vishay"
			(at 176.53 111.76 0)
			(effects
				(font
					(size 1.27 1.27)
					(thickness 0.15)
				)
				(justify left bottom)
				(hide yes)
			)
		)
		(property "License" "Apache-2.0"
			(at 179.07 111.76 0)
			(effects
				(font
					(size 1.27 1.27)
					(thickness 0.15)
				)
				(justify left bottom)
				(hide yes)
			)
		)
		(property "Author" "Antmicro"
			(at 181.61 111.76 0)
			(effects
				(font
					(size 1.27 1.27)
					(thickness 0.15)
				)
				(justify left bottom)
				(hide yes)
			)
		)
		(property "Val" "6k04"
			(at 156.21 129.54 90)
			(effects
				(font
					(size 1.27 1.27)
					(thickness 0.15)
				)
				(justify right)
			)
		)
		(property "Tolerance" "0.1%"
			(at 156.21 132.0799 90)
			(effects
				(font
					(size 1.27 1.27)
				)
				(justify right)
			)
		)
		(pin "2"
		)
		(pin "1"
		)
		(instances
			(project ""
				(path ""
					(reference "R182")
					(unit 1)
				)
			)
			(project "thunderbolt-to-10gbe-adapter"
				(path ""
					(reference "R216")
					(unit 1)
				)
			)
		)
	)
	(symbol
		(lib_id "antmicroTemperatureSensorsAnalogandDigitalOutput:MAX31740ATA+T")
		(at 193.04 132.08 0)
		(unit 1)
		(exclude_from_sim no)
		(in_bom yes)
		(on_board yes)
		(dnp no)
		(fields_autoplaced yes)
		(property "Reference" "U18"
			(at 204.47 124.46 0)
			(effects
				(font
					(size 1.27 1.27)
					(thickness 0.15)
				)
			)
		)
		(property "Value" "MAX31740ATA+T"
			(at 228.6 139.7 0)
			(effects
				(font
					(size 1.27 1.27)
					(thickness 0.15)
				)
				(justify left bottom)
				(hide yes)
			)
		)
		(property "Footprint" "antmicro-footprints:TDFN-8-1EP_2x3x0.75mm_P0.5mm_EP1.75x1.63mm"
			(at 228.6 142.24 0)
			(effects
				(font
					(size 1.27 1.27)
					(thickness 0.15)
				)
				(justify left bottom)
				(hide yes)
			)
		)
		(property "Datasheet" "https://www.analog.com/media/en/technical-documentation/data-sheets/max31740.pdf"
			(at 228.6 144.78 0)
			(effects
				(font
					(size 1.27 1.27)
					(thickness 0.15)
				)
				(justify left bottom)
				(hide yes)
			)
		)
		(property "Description" "Pwm fan speed controller, temperature measurement, Control speed of 2-, 3-, 4- Wire Fans"
			(at 228.6 154.94 0)
			(effects
				(font
					(size 1.27 1.27)
				)
				(justify left bottom)
				(hide yes)
			)
		)
		(property "MPN" "MAX31740ATA+T"
			(at 204.47 127 0)
			(effects
				(font
					(size 1.27 1.27)
					(thickness 0.15)
				)
			)
		)
		(property "Manufacturer" "Analog Devices"
			(at 228.6 147.32 0)
			(effects
				(font
					(size 1.27 1.27)
					(thickness 0.15)
				)
				(justify left bottom)
				(hide yes)
			)
		)
		(property "Author" "Antmicro"
			(at 228.6 149.86 0)
			(effects
				(font
					(size 1.27 1.27)
					(thickness 0.15)
				)
				(justify left bottom)
				(hide yes)
			)
		)
		(property "License" "Apache-2.0"
			(at 228.6 152.4 0)
			(effects
				(font
					(size 1.27 1.27)
					(thickness 0.15)
				)
				(justify left bottom)
				(hide yes)
			)
		)
		(pin "6"
		)
		(pin "9"
		)
		(pin "7"
		)
		(pin "8"
		)
		(pin "3"
		)
		(pin "4"
		)
		(pin "5"
		)
		(pin "1"
		)
		(pin "2"
		)
		(instances
			(project "oculink-to-10gbe-adapter"
				(path ""
					(reference "U14")
					(unit 1)
				)
			)
			(project "thunderbolt-to-10gbe-adapter"
				(path ""
					(reference "U18")
					(unit 1)
				)
			)
		)
	)
	(symbol
		(lib_id "antmicropower:GND")
		(at 180.34 184.15 0)
		(unit 1)
		(exclude_from_sim no)
		(in_bom yes)
		(on_board yes)
		(dnp no)
		(property "Reference" "#PWR0456"
			(at 189.23 186.69 0)
			(effects
				(font
					(size 1.27 1.27)
					(thickness 0.15)
				)
				(justify left bottom)
				(hide yes)
			)
		)
		(property "Value" "GND"
			(at 180.34 187.96 0)
			(effects
				(font
					(size 1.27 1.27)
					(thickness 0.15)
				)
			)
		)
		(property "Footprint" ""
			(at 189.23 191.77 0)
			(effects
				(font
					(size 1.27 1.27)
					(thickness 0.15)
				)
				(justify left bottom)
				(hide yes)
			)
		)
		(property "Datasheet" ""
			(at 189.23 196.85 0)
			(effects
				(font
					(size 1.27 1.27)
					(thickness 0.15)
				)
				(justify left bottom)
				(hide yes)
			)
		)
		(property "Description" ""
			(at 180.34 184.15 0)
			(effects
				(font
					(size 1.27 1.27)
				)
				(hide yes)
			)
		)
		(property "Author" "Antmicro"
			(at 189.23 191.77 0)
			(effects
				(font
					(size 1.27 1.27)
					(thickness 0.15)
				)
				(justify left bottom)
				(hide yes)
			)
		)
		(property "License" "Apache-2.0"
			(at 189.23 194.31 0)
			(effects
				(font
					(size 1.27 1.27)
					(thickness 0.15)
				)
				(justify left bottom)
				(hide yes)
			)
		)
		(pin "1"
		)
		(instances
			(project "oculink-to-10gbe-adapter"
				(path ""
					(reference "#PWR0346")
					(unit 1)
				)
			)
			(project "thunderbolt-to-10gbe-adapter"
				(path ""
					(reference "#PWR0456")
					(unit 1)
				)
			)
		)
	)
	(symbol
		(lib_id "antmicropower:GND")
		(at 237.49 149.86 0)
		(unit 1)
		(exclude_from_sim no)
		(in_bom yes)
		(on_board yes)
		(dnp no)
		(property "Reference" "#PWR0461"
			(at 246.38 152.4 0)
			(effects
				(font
					(size 1.27 1.27)
					(thickness 0.15)
				)
				(justify left bottom)
				(hide yes)
			)
		)
		(property "Value" "GND"
			(at 237.49 153.67 0)
			(effects
				(font
					(size 1.27 1.27)
					(thickness 0.15)
				)
			)
		)
		(property "Footprint" ""
			(at 246.38 157.48 0)
			(effects
				(font
					(size 1.27 1.27)
					(thickness 0.15)
				)
				(justify left bottom)
				(hide yes)
			)
		)
		(property "Datasheet" ""
			(at 246.38 162.56 0)
			(effects
				(font
					(size 1.27 1.27)
					(thickness 0.15)
				)
				(justify left bottom)
				(hide yes)
			)
		)
		(property "Description" ""
			(at 237.49 149.86 0)
			(effects
				(font
					(size 1.27 1.27)
				)
				(hide yes)
			)
		)
		(property "Author" "Antmicro"
			(at 246.38 157.48 0)
			(effects
				(font
					(size 1.27 1.27)
					(thickness 0.15)
				)
				(justify left bottom)
				(hide yes)
			)
		)
		(property "License" "Apache-2.0"
			(at 246.38 160.02 0)
			(effects
				(font
					(size 1.27 1.27)
					(thickness 0.15)
				)
				(justify left bottom)
				(hide yes)
			)
		)
		(pin "1"
		)
		(instances
			(project "oculink-to-10gbe-adapter"
				(path ""
					(reference "#PWR0349")
					(unit 1)
				)
			)
			(project "thunderbolt-to-10gbe-adapter"
				(path ""
					(reference "#PWR0461")
					(unit 1)
				)
			)
		)
	)
	(symbol
		(lib_id "antmicropower:GND")
		(at 218.44 149.86 0)
		(unit 1)
		(exclude_from_sim no)
		(in_bom yes)
		(on_board yes)
		(dnp no)
		(property "Reference" "#PWR0459"
			(at 227.33 152.4 0)
			(effects
				(font
					(size 1.27 1.27)
					(thickness 0.15)
				)
				(justify left bottom)
				(hide yes)
			)
		)
		(property "Value" "GND"
			(at 218.44 153.67 0)
			(effects
				(font
					(size 1.27 1.27)
					(thickness 0.15)
				)
			)
		)
		(property "Footprint" ""
			(at 227.33 157.48 0)
			(effects
				(font
					(size 1.27 1.27)
					(thickness 0.15)
				)
				(justify left bottom)
				(hide yes)
			)
		)
		(property "Datasheet" ""
			(at 227.33 162.56 0)
			(effects
				(font
					(size 1.27 1.27)
					(thickness 0.15)
				)
				(justify left bottom)
				(hide yes)
			)
		)
		(property "Description" ""
			(at 218.44 149.86 0)
			(effects
				(font
					(size 1.27 1.27)
				)
				(hide yes)
			)
		)
		(property "Author" "Antmicro"
			(at 227.33 157.48 0)
			(effects
				(font
					(size 1.27 1.27)
					(thickness 0.15)
				)
				(justify left bottom)
				(hide yes)
			)
		)
		(property "License" "Apache-2.0"
			(at 227.33 160.02 0)
			(effects
				(font
					(size 1.27 1.27)
					(thickness 0.15)
				)
				(justify left bottom)
				(hide yes)
			)
		)
		(pin "1"
		)
		(instances
			(project "oculink-to-10gbe-adapter"
				(path ""
					(reference "#PWR0343")
					(unit 1)
				)
			)
			(project "thunderbolt-to-10gbe-adapter"
				(path ""
					(reference "#PWR0459")
					(unit 1)
				)
			)
		)
	)
	(symbol
		(lib_id "antmicroTVSDiodes:PESD5Z5_0F")
		(at 317.5 149.86 90)
		(mirror x)
		(unit 1)
		(exclude_from_sim no)
		(in_bom yes)
		(on_board yes)
		(dnp no)
		(property "Reference" "D13"
			(at 314.96 151.13 90)
			(effects
				(font
					(size 1.27 1.27)
					(thickness 0.15)
				)
				(justify left)
			)
		)
		(property "Value" "PESD5Z5_0F"
			(at 330.2 165.1 0)
			(effects
				(font
					(size 1.27 1.27)
					(thickness 0.15)
				)
				(justify left bottom)
				(hide yes)
			)
		)
		(property "Footprint" "antmicro-footprints:SOD-523"
			(at 322.58 165.1 0)
			(effects
				(font
					(size 1.27 1.27)
					(thickness 0.15)
				)
				(justify left bottom)
				(hide yes)
			)
		)
		(property "Datasheet" "https://assets.nexperia.com/documents/data-sheet/PESD5Z5_0.pdf"
			(at 325.12 165.1 0)
			(effects
				(font
					(size 1.27 1.27)
					(thickness 0.15)
				)
				(justify left bottom)
				(hide yes)
			)
		)
		(property "Description" "Unidirectional TVS, 30 kV,  SOD-523, 5 V, 89 pF"
			(at 337.82 165.1 0)
			(effects
				(font
					(size 1.27 1.27)
				)
				(justify left bottom)
				(hide yes)
			)
		)
		(property "Manufacturer" "Nexperia"
			(at 327.66 165.1 0)
			(effects
				(font
					(size 1.27 1.27)
					(thickness 0.15)
				)
				(justify left bottom)
				(hide yes)
			)
		)
		(property "MPN" "PESD5Z5.0F"
			(at 314.96 153.67 90)
			(effects
				(font
					(size 1.27 1.27)
					(thickness 0.15)
				)
				(justify left)
			)
		)
		(property "Author" "Antmicro"
			(at 332.74 165.1 0)
			(effects
				(font
					(size 1.27 1.27)
					(thickness 0.15)
				)
				(justify left bottom)
				(hide yes)
			)
		)
		(property "License" "Apache-2.0"
			(at 335.28 165.1 0)
			(effects
				(font
					(size 1.27 1.27)
					(thickness 0.15)
				)
				(justify left bottom)
				(hide yes)
			)
		)
		(pin "2"
		)
		(pin "1"
		)
		(instances
			(project "thunderbolt-to-10gbe-adapter"
				(path ""
					(reference "D13")
					(unit 1)
				)
			)
		)
	)
	(symbol
		(lib_id "antmicropower:GND")
		(at 153.67 147.32 0)
		(unit 1)
		(exclude_from_sim no)
		(in_bom yes)
		(on_board yes)
		(dnp no)
		(property "Reference" "#PWR0453"
			(at 162.56 149.86 0)
			(effects
				(font
					(size 1.27 1.27)
					(thickness 0.15)
				)
				(justify left bottom)
				(hide yes)
			)
		)
		(property "Value" "GND"
			(at 153.67 151.13 0)
			(effects
				(font
					(size 1.27 1.27)
					(thickness 0.15)
				)
			)
		)
		(property "Footprint" ""
			(at 162.56 154.94 0)
			(effects
				(font
					(size 1.27 1.27)
					(thickness 0.15)
				)
				(justify left bottom)
				(hide yes)
			)
		)
		(property "Datasheet" ""
			(at 162.56 160.02 0)
			(effects
				(font
					(size 1.27 1.27)
					(thickness 0.15)
				)
				(justify left bottom)
				(hide yes)
			)
		)
		(property "Description" ""
			(at 153.67 147.32 0)
			(effects
				(font
					(size 1.27 1.27)
				)
				(hide yes)
			)
		)
		(property "Author" "Antmicro"
			(at 162.56 154.94 0)
			(effects
				(font
					(size 1.27 1.27)
					(thickness 0.15)
				)
				(justify left bottom)
				(hide yes)
			)
		)
		(property "License" "Apache-2.0"
			(at 162.56 157.48 0)
			(effects
				(font
					(size 1.27 1.27)
					(thickness 0.15)
				)
				(justify left bottom)
				(hide yes)
			)
		)
		(pin "1"
		)
		(instances
			(project "oculink-to-10gbe-adapter"
				(path ""
					(reference "#PWR0341")
					(unit 1)
				)
			)
			(project "thunderbolt-to-10gbe-adapter"
				(path ""
					(reference "#PWR0453")
					(unit 1)
				)
			)
		)
	)
	(symbol
		(lib_id "antmicroWire2BoardConnectors:Molex_KK_1x4_0470531000")
		(at 281.94 139.7 0)
		(mirror x)
		(unit 1)
		(exclude_from_sim no)
		(in_bom yes)
		(on_board yes)
		(dnp no)
		(property "Reference" "J7"
			(at 288.29 137.16 0)
			(effects
				(font
					(size 1.27 1.27)
					(thickness 0.15)
				)
				(justify left)
			)
		)
		(property "Value" "Molex_KK_1x4_0470531000"
			(at 302.26 129.54 0)
			(effects
				(font
					(size 1.27 1.27)
					(thickness 0.15)
				)
				(justify left bottom)
				(hide yes)
			)
		)
		(property "Footprint" "antmicro-footprints:Conn_Molex_KK_1x4_0470531000"
			(at 302.26 127 0)
			(effects
				(font
					(size 1.27 1.27)
					(thickness 0.15)
				)
				(justify left bottom)
				(hide yes)
			)
		)
		(property "Datasheet" "https://tools.molex.com/pdm_docs/sd/470531000_sd.pdf"
			(at 302.26 124.46 0)
			(effects
				(font
					(size 1.27 1.27)
					(thickness 0.15)
				)
				(justify left bottom)
				(hide yes)
			)
		)
		(property "Description" "Connector Header, THT,  4x1"
			(at 302.26 114.3 0)
			(effects
				(font
					(size 1.27 1.27)
				)
				(justify left bottom)
				(hide yes)
			)
		)
		(property "MPN" "0470531000"
			(at 288.29 134.62 0)
			(effects
				(font
					(size 1.27 1.27)
					(thickness 0.15)
				)
				(justify left)
			)
		)
		(property "Manufacturer" "Molex"
			(at 302.26 121.92 0)
			(effects
				(font
					(size 1.27 1.27)
					(thickness 0.15)
				)
				(justify left bottom)
				(hide yes)
			)
		)
		(property "Author" "Antmicro"
			(at 302.26 119.38 0)
			(effects
				(font
					(size 1.27 1.27)
					(thickness 0.15)
				)
				(justify left bottom)
				(hide yes)
			)
		)
		(property "License" "Apache-2.0"
			(at 302.26 116.84 0)
			(effects
				(font
					(size 1.27 1.27)
					(thickness 0.15)
				)
				(justify left bottom)
				(hide yes)
			)
		)
		(pin "2"
		)
		(pin "1"
		)
		(pin "3"
		)
		(pin "4"
		)
		(instances
			(project "oculink-to-10gbe-adapter"
				(path ""
					(reference "J8")
					(unit 1)
				)
			)
			(project "thunderbolt-to-10gbe-adapter"
				(path ""
					(reference "J7")
					(unit 1)
				)
			)
		)
	)
	(symbol
		(lib_id "antmicroResistors0402:R_10k_0402")
		(at 163.83 137.16 0)
		(unit 1)
		(exclude_from_sim no)
		(in_bom yes)
		(on_board yes)
		(dnp no)
		(property "Reference" "R217"
			(at 166.37 134.62 0)
			(effects
				(font
					(size 1.27 1.27)
					(thickness 0.15)
				)
			)
		)
		(property "Value" "R_10k_0402"
			(at 184.15 149.86 0)
			(effects
				(font
					(size 1.27 1.27)
					(thickness 0.15)
				)
				(justify left bottom)
				(hide yes)
			)
		)
		(property "Footprint" "antmicro-footprints:R_0402_1005Metric"
			(at 184.15 152.4 0)
			(effects
				(font
					(size 1.27 1.27)
					(thickness 0.15)
				)
				(justify left bottom)
				(hide yes)
			)
		)
		(property "Datasheet" "https://www.bourns.com/docs/product-datasheets/cr.pdf"
			(at 184.15 154.94 0)
			(effects
				(font
					(size 1.27 1.27)
					(thickness 0.15)
				)
				(justify left bottom)
				(hide yes)
			)
		)
		(property "Description" "SMD Chip Resistor, 10 kohm, ± 1%, 62.5 mW, 0402 [1005 Metric], Thick Film, General Purpose"
			(at 184.15 167.64 0)
			(effects
				(font
					(size 1.27 1.27)
				)
				(justify left bottom)
				(hide yes)
			)
		)
		(property "MPN" "CR0402-FX-1002GLF"
			(at 184.15 157.48 0)
			(effects
				(font
					(size 1.27 1.27)
					(thickness 0.15)
				)
				(justify left bottom)
				(hide yes)
			)
		)
		(property "Manufacturer" "Bourns"
			(at 184.15 160.02 0)
			(effects
				(font
					(size 1.27 1.27)
					(thickness 0.15)
				)
				(justify left bottom)
				(hide yes)
			)
		)
		(property "License" "Apache-2.0"
			(at 184.15 162.56 0)
			(effects
				(font
					(size 1.27 1.27)
					(thickness 0.15)
				)
				(justify left bottom)
				(hide yes)
			)
		)
		(property "Author" "Antmicro"
			(at 184.15 165.1 0)
			(effects
				(font
					(size 1.27 1.27)
					(thickness 0.15)
				)
				(justify left bottom)
				(hide yes)
			)
		)
		(property "Val" "10k"
			(at 166.37 139.7 0)
			(effects
				(font
					(size 1.27 1.27)
					(thickness 0.15)
				)
			)
		)
		(property "Tolerance" "1%"
			(at 184.15 147.32 0)
			(effects
				(font
					(size 1.27 1.27)
				)
				(justify left bottom)
				(hide yes)
			)
		)
		(pin "2"
		)
		(pin "1"
		)
		(instances
			(project ""
				(path ""
					(reference "R175")
					(unit 1)
				)
			)
			(project "thunderbolt-to-10gbe-adapter"
				(path ""
					(reference "R217")
					(unit 1)
				)
			)
		)
	)
	(symbol
		(lib_id "antmicroResistors0402:R_10k_0402")
		(at 180.34 171.45 270)
		(mirror x)
		(unit 1)
		(exclude_from_sim no)
		(in_bom yes)
		(on_board yes)
		(dnp no)
		(property "Reference" "R218"
			(at 179.07 167.64 90)
			(effects
				(font
					(size 1.27 1.27)
					(thickness 0.15)
				)
				(justify right)
			)
		)
		(property "Value" "R_10k_0402"
			(at 167.64 151.13 0)
			(effects
				(font
					(size 1.27 1.27)
					(thickness 0.15)
				)
				(justify left bottom)
				(hide yes)
			)
		)
		(property "Footprint" "antmicro-footprints:R_0402_1005Metric"
			(at 165.1 151.13 0)
			(effects
				(font
					(size 1.27 1.27)
					(thickness 0.15)
				)
				(justify left bottom)
				(hide yes)
			)
		)
		(property "Datasheet" "https://www.bourns.com/docs/product-datasheets/cr.pdf"
			(at 162.56 151.13 0)
			(effects
				(font
					(size 1.27 1.27)
					(thickness 0.15)
				)
				(justify left bottom)
				(hide yes)
			)
		)
		(property "Description" "SMD Chip Resistor, 10 kohm, ± 1%, 62.5 mW, 0402 [1005 Metric], Thick Film, General Purpose"
			(at 149.86 151.13 0)
			(effects
				(font
					(size 1.27 1.27)
				)
				(justify left bottom)
				(hide yes)
			)
		)
		(property "MPN" "CR0402-FX-1002GLF"
			(at 160.02 151.13 0)
			(effects
				(font
					(size 1.27 1.27)
					(thickness 0.15)
				)
				(justify left bottom)
				(hide yes)
			)
		)
		(property "Manufacturer" "Bourns"
			(at 157.48 151.13 0)
			(effects
				(font
					(size 1.27 1.27)
					(thickness 0.15)
				)
				(justify left bottom)
				(hide yes)
			)
		)
		(property "License" "Apache-2.0"
			(at 154.94 151.13 0)
			(effects
				(font
					(size 1.27 1.27)
					(thickness 0.15)
				)
				(justify left bottom)
				(hide yes)
			)
		)
		(property "Author" "Antmicro"
			(at 152.4 151.13 0)
			(effects
				(font
					(size 1.27 1.27)
					(thickness 0.15)
				)
				(justify left bottom)
				(hide yes)
			)
		)
		(property "Val" "10k"
			(at 179.07 170.18 90)
			(effects
				(font
					(size 1.27 1.27)
					(thickness 0.15)
				)
				(justify right)
			)
		)
		(property "Tolerance" "1%"
			(at 170.18 151.13 0)
			(effects
				(font
					(size 1.27 1.27)
				)
				(justify left bottom)
				(hide yes)
			)
		)
		(pin "2"
		)
		(pin "1"
		)
		(instances
			(project "oculink-to-10gbe-adapter"
				(path ""
					(reference "R179")
					(unit 1)
				)
			)
			(project "thunderbolt-to-10gbe-adapter"
				(path ""
					(reference "R218")
					(unit 1)
				)
			)
		)
	)
	(symbol
		(lib_id "antmicropower:+5V")
		(at 279.4 128.27 0)
		(unit 1)
		(exclude_from_sim no)
		(in_bom yes)
		(on_board yes)
		(dnp no)
		(fields_autoplaced yes)
		(property "Reference" "#PWR0462"
			(at 294.64 130.81 0)
			(effects
				(font
					(size 1.27 1.27)
					(thickness 0.15)
				)
				(justify left bottom)
				(hide yes)
			)
		)
		(property "Value" "+5V"
			(at 279.4 123.19 0)
			(effects
				(font
					(size 1.27 1.27)
					(thickness 0.15)
				)
			)
		)
		(property "Footprint" ""
			(at 294.64 135.89 0)
			(effects
				(font
					(size 1.27 1.27)
					(thickness 0.15)
				)
				(justify left bottom)
				(hide yes)
			)
		)
		(property "Datasheet" ""
			(at 294.64 138.43 0)
			(effects
				(font
					(size 1.27 1.27)
					(thickness 0.15)
				)
				(justify left bottom)
				(hide yes)
			)
		)
		(property "Description" ""
			(at 294.64 140.97 0)
			(effects
				(font
					(size 1.27 1.27)
				)
				(justify left bottom)
				(hide yes)
			)
		)
		(property "Author" "Antmicro"
			(at 294.64 135.89 0)
			(effects
				(font
					(size 1.27 1.27)
					(thickness 0.15)
				)
				(justify left bottom)
				(hide yes)
			)
		)
		(property "License" "Apache-2.0"
			(at 294.64 138.43 0)
			(effects
				(font
					(size 1.27 1.27)
					(thickness 0.15)
				)
				(justify left bottom)
				(hide yes)
			)
		)
		(pin "1"
		)
		(instances
			(project "thunderbolt-to-10gbe-adapter"
				(path ""
					(reference "#PWR0462")
					(unit 1)
				)
			)
		)
	)
	(symbol
		(lib_id "antmicroResistors0402:R_1k_0402")
		(at 180.34 181.61 270)
		(mirror x)
		(unit 1)
		(exclude_from_sim no)
		(in_bom yes)
		(on_board yes)
		(dnp no)
		(property "Reference" "R219"
			(at 179.07 177.8 90)
			(effects
				(font
					(size 1.27 1.27)
					(thickness 0.15)
				)
				(justify right)
			)
		)
		(property "Value" "R_1k_0402"
			(at 167.64 161.29 0)
			(effects
				(font
					(size 1.27 1.27)
					(thickness 0.15)
				)
				(justify left bottom)
				(hide yes)
			)
		)
		(property "Footprint" "antmicro-footprints:R_0402_1005Metric"
			(at 165.1 161.29 0)
			(effects
				(font
					(size 1.27 1.27)
					(thickness 0.15)
				)
				(justify left bottom)
				(hide yes)
			)
		)
		(property "Datasheet" "https://www.bourns.com/docs/product-datasheets/cr.pdf"
			(at 162.56 161.29 0)
			(effects
				(font
					(size 1.27 1.27)
					(thickness 0.15)
				)
				(justify left bottom)
				(hide yes)
			)
		)
		(property "Description" "SMD Chip Resistor, 1 kohm, ± 1%, 63 mW, 0402 [1005 Metric], Thick Film, General Purpose"
			(at 149.86 161.29 0)
			(effects
				(font
					(size 1.27 1.27)
				)
				(justify left bottom)
				(hide yes)
			)
		)
		(property "MPN" "CR0402-FX-1001GLF"
			(at 160.02 161.29 0)
			(effects
				(font
					(size 1.27 1.27)
					(thickness 0.15)
				)
				(justify left bottom)
				(hide yes)
			)
		)
		(property "Manufacturer" "Bourns"
			(at 157.48 161.29 0)
			(effects
				(font
					(size 1.27 1.27)
					(thickness 0.15)
				)
				(justify left bottom)
				(hide yes)
			)
		)
		(property "License" "Apache-2.0"
			(at 154.94 161.29 0)
			(effects
				(font
					(size 1.27 1.27)
					(thickness 0.15)
				)
				(justify left bottom)
				(hide yes)
			)
		)
		(property "Author" "Antmicro"
			(at 152.4 161.29 0)
			(effects
				(font
					(size 1.27 1.27)
					(thickness 0.15)
				)
				(justify left bottom)
				(hide yes)
			)
		)
		(property "Val" "1k"
			(at 179.07 180.34 90)
			(effects
				(font
					(size 1.27 1.27)
					(thickness 0.15)
				)
				(justify right)
			)
		)
		(property "Tolerance" "1%"
			(at 170.18 161.29 0)
			(effects
				(font
					(size 1.27 1.27)
				)
				(justify left bottom)
				(hide yes)
			)
		)
		(pin "2"
		)
		(pin "1"
		)
		(instances
			(project ""
				(path ""
					(reference "R178")
					(unit 1)
				)
			)
			(project "thunderbolt-to-10gbe-adapter"
				(path ""
					(reference "R219")
					(unit 1)
				)
			)
		)
	)
	(symbol
		(lib_id "antmicroResistors0402:R_0R_0402")
		(at 193.04 171.45 90)
		(unit 1)
		(exclude_from_sim no)
		(in_bom yes)
		(on_board yes)
		(dnp yes)
		(property "Reference" "R220"
			(at 194.31 167.64 90)
			(effects
				(font
					(size 1.27 1.27)
					(thickness 0.15)
				)
				(justify right)
			)
		)
		(property "Value" "R_0R_0402"
			(at 205.74 151.13 0)
			(effects
				(font
					(size 1.27 1.27)
					(thickness 0.15)
				)
				(justify left bottom)
				(hide yes)
			)
		)
		(property "Footprint" "antmicro-footprints:R_0402_1005Metric"
			(at 208.28 151.13 0)
			(effects
				(font
					(size 1.27 1.27)
					(thickness 0.15)
				)
				(justify left bottom)
				(hide yes)
			)
		)
		(property "Datasheet" "https://industrial.panasonic.com/cdbs/www-data/pdf/RDA0000/AOA0000C301.pdf"
			(at 210.82 151.13 0)
			(effects
				(font
					(size 1.27 1.27)
					(thickness 0.15)
				)
				(justify left bottom)
				(hide yes)
			)
		)
		(property "Description" "SMD Chip Resistor, Jumper, 0 ohm, 100 mW, 0402 [1005 Metric], Thick Film, General Purpose"
			(at 226.06 151.13 0)
			(effects
				(font
					(size 1.27 1.27)
				)
				(justify left bottom)
				(hide yes)
			)
		)
		(property "MPN" "ERJ2GE0R00X"
			(at 213.36 151.13 0)
			(effects
				(font
					(size 1.27 1.27)
					(thickness 0.15)
				)
				(justify left bottom)
				(hide yes)
			)
		)
		(property "Manufacturer" "Panasonic"
			(at 215.9 151.13 0)
			(effects
				(font
					(size 1.27 1.27)
					(thickness 0.15)
				)
				(justify left bottom)
				(hide yes)
			)
		)
		(property "License" "Apache-2.0"
			(at 218.44 151.13 0)
			(effects
				(font
					(size 1.27 1.27)
					(thickness 0.15)
				)
				(justify left bottom)
				(hide yes)
			)
		)
		(property "Author" "Antmicro"
			(at 220.98 151.13 0)
			(effects
				(font
					(size 1.27 1.27)
					(thickness 0.15)
				)
				(justify left bottom)
				(hide yes)
			)
		)
		(property "Val" "0R"
			(at 194.31 170.18 90)
			(effects
				(font
					(size 1.27 1.27)
					(thickness 0.15)
				)
				(justify right)
			)
		)
		(property "Tolerance" "~"
			(at 203.2 151.13 0)
			(effects
				(font
					(size 1.27 1.27)
				)
				(justify left bottom)
				(hide yes)
			)
		)
		(property "Current" "1A"
			(at 223.52 151.13 0)
			(effects
				(font
					(size 1.27 1.27)
					(thickness 0.15)
				)
				(justify left bottom)
				(hide yes)
			)
		)
		(pin "2"
		)
		(pin "1"
		)
		(instances
			(project "oculink-to-10gbe-adapter"
				(path ""
					(reference "R177")
					(unit 1)
				)
			)
			(project "thunderbolt-to-10gbe-adapter"
				(path ""
					(reference "R220")
					(unit 1)
				)
			)
		)
	)
	(symbol
		(lib_id "antmicropower:+5V")
		(at 185.42 119.38 0)
		(unit 1)
		(exclude_from_sim no)
		(in_bom yes)
		(on_board yes)
		(dnp no)
		(fields_autoplaced yes)
		(property "Reference" "#PWR0457"
			(at 200.66 121.92 0)
			(effects
				(font
					(size 1.27 1.27)
					(thickness 0.15)
				)
				(justify left bottom)
				(hide yes)
			)
		)
		(property "Value" "+5V"
			(at 185.42 114.3 0)
			(effects
				(font
					(size 1.27 1.27)
					(thickness 0.15)
				)
			)
		)
		(property "Footprint" ""
			(at 200.66 127 0)
			(effects
				(font
					(size 1.27 1.27)
					(thickness 0.15)
				)
				(justify left bottom)
				(hide yes)
			)
		)
		(property "Datasheet" ""
			(at 200.66 129.54 0)
			(effects
				(font
					(size 1.27 1.27)
					(thickness 0.15)
				)
				(justify left bottom)
				(hide yes)
			)
		)
		(property "Description" ""
			(at 200.66 132.08 0)
			(effects
				(font
					(size 1.27 1.27)
				)
				(justify left bottom)
				(hide yes)
			)
		)
		(property "Author" "Antmicro"
			(at 200.66 127 0)
			(effects
				(font
					(size 1.27 1.27)
					(thickness 0.15)
				)
				(justify left bottom)
				(hide yes)
			)
		)
		(property "License" "Apache-2.0"
			(at 200.66 129.54 0)
			(effects
				(font
					(size 1.27 1.27)
					(thickness 0.15)
				)
				(justify left bottom)
				(hide yes)
			)
		)
		(pin "1"
		)
		(instances
			(project "thunderbolt-to-10gbe-adapter"
				(path ""
					(reference "#PWR0457")
					(unit 1)
				)
			)
		)
	)
)
